(kicad_pcb
	(version 20260206)
	(generator "pcbnew")
	(generator_version "10.0")
	(general
		(thickness 1.21888)
		(legacy_teardrops no)
	)
	(paper "A4")
	(title_block
		(title "timecard-v9 — TimeCard-DC-V9_EXP.PcbDoc")
		(comment 1 "Time Appliance Project (Time Card) / footprints 192-200 of 402")
	)
	(layers
		(0 "F.Cu" signal "TOP")
		(4 "In1.Cu" signal "SGND")
		(6 "In2.Cu" signal "IN1")
		(8 "In3.Cu" signal "IN2")
		(10 "In4.Cu" signal "SGND1")
		(2 "B.Cu" signal "BOTTOM")
		(9 "F.Adhes" user "F.Adhesive")
		(11 "B.Adhes" user "B.Adhesive")
		(13 "F.Paste" user "Top Paste")
		(15 "B.Paste" user "Bottom Paste")
		(5 "F.SilkS" user "Top Overlay")
		(7 "B.SilkS" user "Bottom Overlay")
		(1 "F.Mask" user "Top Solder")
		(3 "B.Mask" user "Bottom Solder")
		(17 "Dwgs.User" user "User.Drawings")
		(19 "Cmts.User" user "User.Comments")
		(21 "Eco1.User" user "User.Eco1")
		(23 "Eco2.User" user "User.Eco2")
		(25 "Edge.Cuts" user)
		(27 "Margin" user)
		(31 "F.CrtYd" user "Top Courtyard")
		(29 "B.CrtYd" user "Bottom Courtyard")
		(35 "F.Fab" user "Top Component Center")
		(33 "B.Fab" user "Bottom Component Center")
	)
	(footprint "Vault:RESC1005X40X25NL05T05"
		(layer "F.Cu")
		(at 151.9216 116.9162)
		(property "Reference" "R111"
			(at -2.2666 -0.102389 0)
			(unlocked yes)
			(layer "F.SilkS")
			(effects
				(font
					(size 0.762 0.762)
					(thickness 0.2032)
				)
			)
		)
		(property "Value" "27_1%_0402"
			(at -2.732271 7.35092 270)
			(unlocked yes)
			(layer "F.SilkS")
			(hide yes)
			(effects
				(font
					(size 0.762 0.762)
					(thickness 0.2032)
				)
			)
		)
		(sheetname "08-DIPSwitches_I2C")
		(sheetfile "08-DIPSwitches_I2C.kicad_sch")
		(duplicate_pad_numbers_are_jumpers no)
		(pad "1" smd rect
			(at -0.45 0 90)
			(size 0.55 0.55)
			(layers "F.Cu" "F.Mask" "F.Paste")
			(net "MAC_FPGA_UART_RX")
		)
		(pad "2" smd rect
			(at 0.45 0 90)
			(size 0.55 0.55)
			(layers "F.Cu" "F.Mask" "F.Paste")
			(net "NetR111_2")
		)
	)
	(footprint "Vault:FP-RUT0012A-MFG"
		(layer "F.Cu")
		(at 120.3216 79.1162 90)
		(property "Reference" "U31"
			(at 1.573069 0.203205 0)
			(unlocked yes)
			(layer "F.SilkS")
			(effects
				(font
					(size 0.762 0.762)
					(thickness 0.2032)
				)
			)
		)
		(property "Value" "TMUX1072RUTR"
			(at 7.401265 3.164071 90)
			(unlocked yes)
			(layer "F.SilkS")
			(hide yes)
			(effects
				(font
					(size 0.762 0.762)
					(thickness 0.2032)
				)
			)
		)
		(sheetname "11-M2_RCB_MUX")
		(sheetfile "11-M2_RCB_MUX.kicad_sch")
		(duplicate_pad_numbers_are_jumpers no)
		(fp_line
			(start -0.9 -1.525)
			(end 0.9 -1.525)
			(stroke
				(width 0.2)
				(type solid)
			)
			(layer "F.SilkS")
		)
		(fp_line
			(start -0.9 1.525)
			(end 0.9 1.525)
			(stroke
				(width 0.2)
				(type solid)
			)
			(layer "F.SilkS")
		)
		(fp_circle
			(center -1.575 -0.8)
			(end -1.45 -0.8)
			(stroke
				(width 0.25)
				(type solid)
			)
			(fill no)
			(layer "F.SilkS")
		)
		(fp_rect
			(start 0.350035 -0.699955)
			(end 0.850045 -0.899955)
			(stroke
				(width 0)
				(type default)
			)
			(fill yes)
			(layer "F.Paste")
		)
		(fp_rect
			(start -0.10003 -0.49997)
			(end 0.09997 -0.99997)
			(stroke
				(width 0)
				(type default)
			)
			(fill yes)
			(layer "F.Paste")
		)
		(fp_rect
			(start 0.34996 -0.30004)
			(end 0.84996 -0.50004)
			(stroke
				(width 0)
				(type default)
			)
			(fill yes)
			(layer "F.Paste")
		)
		(fp_rect
			(start -0.849965 -0.299955)
			(end -0.349955 -0.499955)
			(stroke
				(width 0)
				(type default)
			)
			(fill yes)
			(layer "F.Paste")
		)
		(fp_rect
			(start 0.34996 0.09996)
			(end 0.84996 -0.10004)
			(stroke
				(width 0)
				(type default)
			)
			(fill yes)
			(layer "F.Paste")
		)
		(fp_rect
			(start -0.84996 0.10004)
			(end -0.34996 -0.09996)
			(stroke
				(width 0)
				(type default)
			)
			(fill yes)
			(layer "F.Paste")
		)
		(fp_rect
			(start 0.34996 0.49996)
			(end 0.84996 0.29996)
			(stroke
				(width 0)
				(type default)
			)
			(fill yes)
			(layer "F.Paste")
		)
		(fp_rect
			(start -0.84996 0.50004)
			(end -0.34996 0.30004)
			(stroke
				(width 0)
				(type default)
			)
			(fill yes)
			(layer "F.Paste")
		)
		(fp_rect
			(start -0.85004 0.89996)
			(end -0.35004 0.69996)
			(stroke
				(width 0)
				(type default)
			)
			(fill yes)
			(layer "F.Paste")
		)
		(fp_rect
			(start 0.35004 0.90005)
			(end 0.85004 0.70005)
			(stroke
				(width 0)
				(type default)
			)
			(fill yes)
			(layer "F.Paste")
		)
		(fp_rect
			(start -0.099965 0.999975)
			(end 0.100035 0.499965)
			(stroke
				(width 0)
				(type default)
			)
			(fill yes)
			(layer "F.Paste")
		)
		(fp_poly
			(pts
				(xy -0.5 -1) (xy -0.35 -1) (xy -0.35 -0.7) (xy -0.85 -0.7) (xy -0.85 -0.9) (xy -0.5 -0.9)
			)
			(stroke
				(width 0)
				(type default)
			)
			(fill yes)
			(layer "F.Paste")
		)
		(fp_line
			(start 1.05 -1.2)
			(end 1.05 1.2)
			(stroke
				(width 0.2)
				(type solid)
			)
			(layer "F.CrtYd")
		)
		(fp_line
			(start -1.05 -1.2)
			(end 1.05 -1.2)
			(stroke
				(width 0.2)
				(type solid)
			)
			(layer "F.CrtYd")
		)
		(fp_line
			(start -1.05 -1.2)
			(end -1.05 1.2)
			(stroke
				(width 0.2)
				(type solid)
			)
			(layer "F.CrtYd")
		)
		(fp_line
			(start -1.05 1.2)
			(end 1.05 1.2)
			(stroke
				(width 0.2)
				(type solid)
			)
			(layer "F.CrtYd")
		)
		(fp_line
			(start 1.05 -1.2)
			(end 1.05 1.2)
			(stroke
				(width 0.2)
				(type solid)
			)
			(layer "F.Fab")
		)
		(fp_line
			(start -1.05 -1.2)
			(end 1.05 -1.2)
			(stroke
				(width 0.2)
				(type solid)
			)
			(layer "F.Fab")
		)
		(fp_line
			(start -1.05 -1.2)
			(end -1.05 1.2)
			(stroke
				(width 0.2)
				(type solid)
			)
			(layer "F.Fab")
		)
		(fp_line
			(start 0 -0.5)
			(end 0 0.5)
			(stroke
				(width 0.1)
				(type solid)
			)
			(layer "F.Fab")
		)
		(fp_line
			(start -0.5 0)
			(end 0.5 0)
			(stroke
				(width 0.1)
				(type solid)
			)
			(layer "F.Fab")
		)
		(fp_line
			(start -1.05 1.2)
			(end 1.05 1.2)
			(stroke
				(width 0.2)
				(type solid)
			)
			(layer "F.Fab")
		)
		(fp_text user "${REFERENCE}"
			(at -0.00001 0.09602 90)
			(unlocked yes)
			(layer "F.Fab")
			(effects
				(font
					(face "Arial")
					(size 0.63 0.63)
					(thickness 0.1)
				)
				(justify left bottom)
			)
		)
		(pad "" smd custom
			(at -0.5 -1.1)
			(size 0.000001 0.000001)
			(layers "F.Cu" "F.Mask")
			(solder_mask_margin 0)
			(thermal_bridge_angle 90)
			(options
				(clearance outline)
				(anchor circle)
			)
			(primitives
				(gr_poly
					(pts
						(xy 0 0) (xy 0 -0.15) (xy 0.4 -0.15) (xy 0.4 0.45) (xy 0.2 0.45) (xy 0.2 0)
					)
					(width 0)
					(fill yes)
				)
			)
		)
		(pad "1" smd circle
			(at -0.45 -0.8 90)
			(size 0.18 0.18)
			(layers "F.Cu" "F.Mask" "F.Paste")
			(net "DIP_SW_GPS1_SEL")
			(solder_mask_margin 0)
			(solder_paste_margin -1000)
			(thermal_bridge_angle 90)
		)
		(pad "2" smd rect
			(at -0.65 -0.4 90)
			(size 0.6 0.2)
			(layers "F.Cu" "F.Mask" "F.Paste")
			(net "M2_GPS1_PIN11")
			(solder_mask_margin 0)
			(solder_paste_margin -1000)
		)
		(pad "3" smd rect
			(at -0.65 0 90)
			(size 0.6 0.2)
			(layers "F.Cu" "F.Mask" "F.Paste")
			(net "GND")
			(solder_mask_margin 0)
			(solder_paste_margin -1000)
		)
		(pad "4" smd rect
			(at -0.65 0.4 90)
			(size 0.6 0.2)
			(layers "F.Cu" "F.Mask" "F.Paste")
			(net "M2_GPS1_PIN12")
			(solder_mask_margin 0)
			(solder_paste_margin -1000)
		)
		(pad "5" smd rect
			(at -0.65 0.8 90)
			(size 0.6 0.2)
			(layers "F.Cu" "F.Mask" "F.Paste")
			(net "DIP_SW_GPS1_SEL")
			(solder_mask_margin 0)
			(solder_paste_margin -1000)
		)
		(pad "6" smd rect
			(at 0 0.8 90)
			(size 0.2 0.6)
			(layers "F.Cu" "F.Mask" "F.Paste")
			(net "GND")
			(solder_mask_margin 0)
			(solder_paste_margin -1000)
		)
		(pad "7" smd rect
			(at 0.65 0.8 90)
			(size 0.6 0.2)
			(layers "F.Cu" "F.Mask" "F.Paste")
			(net "NetR177_1")
			(solder_mask_margin 0)
			(solder_paste_margin -1000)
		)
		(pad "8" smd rect
			(at 0.65 0.4 90)
			(size 0.6 0.2)
			(layers "F.Cu" "F.Mask" "F.Paste")
			(net "RCB_GPS1_PIN12")
			(solder_mask_margin 0)
			(solder_paste_margin -1000)
		)
		(pad "9" smd rect
			(at 0.65 0 90)
			(size 0.6 0.2)
			(layers "F.Cu" "F.Mask" "F.Paste")
			(net "+3.3V")
			(solder_mask_margin 0)
			(solder_paste_margin -1000)
		)
		(pad "10" smd rect
			(at 0.65 -0.4 90)
			(size 0.6 0.2)
			(layers "F.Cu" "F.Mask" "F.Paste")
			(net "RCB_GPS1_PIN11")
			(solder_mask_margin 0)
			(solder_paste_margin -1000)
		)
		(pad "11" smd rect
			(at 0.65 -0.8 90)
			(size 0.6 0.2)
			(layers "F.Cu" "F.Mask" "F.Paste")
			(net "NetR176_1")
			(solder_mask_margin 0)
			(solder_paste_margin -1000)
		)
		(pad "12" smd rect
			(at 0 -0.8 90)
			(size 0.2 0.6)
			(layers "F.Cu" "F.Mask" "F.Paste")
			(net "GND")
			(solder_mask_margin 0)
			(solder_paste_margin -1000)
		)
	)
	(footprint "Vault:TECO-1909763-1_V"
		(layer "F.Cu")
		(at 77.19563 108.6162 -90)
		(property "Reference" "J2"
			(at -2.773069 0.445435 0)
			(unlocked yes)
			(layer "F.SilkS")
			(effects
				(font
					(size 0.762 0.762)
					(thickness 0.2286)
				)
			)
		)
		(property "Value" "1909763-1"
			(at 4.582685 3.722871 270)
			(unlocked yes)
			(layer "F.SilkS")
			(hide yes)
			(effects
				(font
					(size 0.762 0.762)
					(thickness 0.2286)
				)
			)
		)
		(sheetname "01-USER_IO")
		(sheetfile "01-USER_IO.kicad_sch")
		(duplicate_pad_numbers_are_jumpers no)
		(fp_line
			(start 0.55 -1.3)
			(end -0.55 -1.3)
			(stroke
				(width 0.2)
				(type solid)
			)
			(layer "F.SilkS")
		)
		(fp_circle
			(center -1.778 1.65)
			(end -1.903 1.65)
			(stroke
				(width 0.25)
				(type solid)
			)
			(fill no)
			(layer "F.SilkS")
		)
		(pad "1" smd rect
			(at -1.475 0 270)
			(size 1.05 2.2)
			(layers "F.Cu" "F.Mask" "F.Paste")
			(net "GND")
		)
		(pad "2" smd rect
			(at 0 1.525 270)
			(size 1 1.05)
			(layers "F.Cu" "F.Mask" "F.Paste")
			(net "NetAN2_1")
		)
		(pad "3" smd rect
			(at 1.475 0 270)
			(size 1.05 2.2)
			(layers "F.Cu" "F.Mask" "F.Paste")
			(net "GND")
		)
	)
	(footprint "Vault:RESC3116X65X50ML20T20"
		(layer "F.Cu")
		(at 140.7716 90.9662)
		(property "Reference" "R45"
			(at 4.0786 -0.023079 0)
			(unlocked yes)
			(layer "F.SilkS")
			(effects
				(font
					(size 0.762 0.762)
					(thickness 0.2286)
				)
			)
		)
		(property "Value" "0_5%_1206"
			(at 4.35396 3.291071 0)
			(unlocked yes)
			(layer "F.SilkS")
			(hide yes)
			(effects
				(font
					(size 0.762 0.762)
					(thickness 0.2286)
				)
			)
		)
		(sheetname "06-MAC")
		(sheetfile "06-MAC.kicad_sch")
		(duplicate_pad_numbers_are_jumpers no)
		(fp_line
			(start -0.35 -0.85)
			(end 0.35 -0.85)
			(stroke
				(width 0.2)
				(type solid)
			)
			(layer "F.SilkS")
		)
		(fp_line
			(start -0.35 0.85)
			(end 0.35 0.85)
			(stroke
				(width 0.2)
				(type solid)
			)
			(layer "F.SilkS")
		)
		(pad "1" smd rect
			(at -1.475 0 90)
			(size 1.9 1.45)
			(layers "F.Cu" "F.Mask" "F.Paste")
			(net "MAC_VCC")
		)
		(pad "2" smd rect
			(at 1.475 0 90)
			(size 1.9 1.45)
			(layers "F.Cu" "F.Mask" "F.Paste")
			(net "+5.0V")
		)
	)
	(footprint "Vault:RESC1005X40X25NL10T10"
		(layer "F.Cu")
		(at 172.9216 118.8162 -90)
		(property "Reference" "R117"
			(at 2.7032 0.045011 270)
			(unlocked yes)
			(layer "F.SilkS")
			(effects
				(font
					(size 0.762 0.762)
					(thickness 0.2032)
				)
			)
		)
		(property "Value" "4.7K_1%_0402"
			(at -2.732271 8.747465 180)
			(unlocked yes)
			(layer "F.SilkS")
			(hide yes)
			(effects
				(font
					(size 0.762 0.762)
					(thickness 0.2032)
				)
			)
		)
		(sheetname "08-DIPSwitches_I2C")
		(sheetfile "08-DIPSwitches_I2C.kicad_sch")
		(duplicate_pad_numbers_are_jumpers no)
		(pad "1" smd rect
			(at -0.425 0)
			(size 0.6 0.65)
			(layers "F.Cu" "F.Mask" "F.Paste")
			(net "SENS_I2C_SDA")
		)
		(pad "2" smd rect
			(at 0.425 0)
			(size 0.6 0.65)
			(layers "F.Cu" "F.Mask" "F.Paste")
			(net "+3.3V")
		)
	)
	(footprint "SamacSys:155124M173200"
		(layer "F.Cu")
		(at 67.4466 101.4162 90)
		(property "Reference" "D15"
			(at -0.8286 1.248069 270)
			(unlocked yes)
			(layer "F.SilkS")
			(effects
				(font
					(size 0.762 0.762)
					(thickness 0.2286)
				)
			)
		)
		(property "Value" "155124M173200"
			(at 7.1471 2.605271 90)
			(unlocked yes)
			(layer "F.SilkS")
			(hide yes)
			(effects
				(font
					(size 0.762 0.762)
					(thickness 0.2286)
				)
			)
		)
		(sheetname "02-USER_IO_STATUS")
		(sheetfile "02-USER_IO_STATUS.kicad_sch")
		(duplicate_pad_numbers_are_jumpers no)
		(fp_line
			(start -0.8 0.5)
			(end 0.8 0.5)
			(stroke
				(width 0.1)
				(type solid)
			)
			(layer "F.SilkS")
		)
		(fp_arc
			(start -2 -0.1)
			(mid -1.95 -0.05)
			(end -2 0)
			(stroke
				(width 0.381)
				(type solid)
			)
			(layer "F.SilkS")
		)
		(fp_arc
			(start -2 0)
			(mid -2.05 -0.05)
			(end -2 -0.1)
			(stroke
				(width 0.381)
				(type solid)
			)
			(layer "F.SilkS")
		)
		(pad "1" smd rect
			(at -1.4 0 180)
			(size 0.9 0.6)
			(layers "F.Cu" "F.Mask" "F.Paste")
			(net "+3.3V")
		)
		(pad "2" smd rect
			(at -0.45 -0.325 90)
			(size 0.6 0.55)
			(layers "F.Cu" "F.Mask" "F.Paste")
			(net "NetD15_2")
		)
		(pad "3" smd rect
			(at 0.45 -0.325 90)
			(size 0.6 0.55)
			(layers "F.Cu" "F.Mask" "F.Paste")
			(net "NetD15_3")
		)
		(pad "4" smd rect
			(at 1.4 0 180)
			(size 0.9 0.6)
			(layers "F.Cu" "F.Mask" "F.Paste")
			(net "NetD15_4")
		)
	)
	(footprint "Vault:FP-CC0402-MFG"
		(layer "F.Cu")
		(at 227.2216 121.4162 180)
		(property "Reference" "C91"
			(at 2.171395 -0.426931 0)
			(unlocked yes)
			(layer "F.SilkS")
			(effects
				(font
					(size 0.762 0.762)
					(thickness 0.2286)
				)
			)
		)
		(property "Value" "10nF_50V_0402"
			(at 9.02662 2.389351 180)
			(unlocked yes)
			(layer "F.SilkS")
			(hide yes)
			(effects
				(font
					(size 0.762 0.762)
					(thickness 0.2286)
				)
			)
		)
		(sheetname "09-USBUart_PPSMUX_UARTMUX")
		(sheetfile "09-USBUart_PPSMUX_UARTMUX.kicad_sch")
		(duplicate_pad_numbers_are_jumpers no)
		(fp_line
			(start 0.525 -0.675)
			(end -0.525 -0.675)
			(stroke
				(width 0.2)
				(type solid)
			)
			(layer "F.SilkS")
		)
		(fp_line
			(start 0.51967 0.68067)
			(end -0.53033 0.68067)
			(stroke
				(width 0.2)
				(type solid)
			)
			(layer "F.SilkS")
		)
		(fp_line
			(start 0.875 0.475)
			(end -0.875 0.475)
			(stroke
				(width 0.2)
				(type solid)
			)
			(layer "F.CrtYd")
		)
		(fp_line
			(start 0.875 -0.475)
			(end 0.875 0.475)
			(stroke
				(width 0.2)
				(type solid)
			)
			(layer "F.CrtYd")
		)
		(fp_line
			(start 0.875 -0.475)
			(end -0.875 -0.475)
			(stroke
				(width 0.2)
				(type solid)
			)
			(layer "F.CrtYd")
		)
		(fp_line
			(start -0.875 -0.475)
			(end -0.875 0.475)
			(stroke
				(width 0.2)
				(type solid)
			)
			(layer "F.CrtYd")
		)
		(fp_line
			(start 0.875 0.475)
			(end -0.875 0.475)
			(stroke
				(width 0.2)
				(type solid)
			)
			(layer "F.Fab")
		)
		(fp_line
			(start 0.875 -0.475)
			(end 0.875 0.475)
			(stroke
				(width 0.2)
				(type solid)
			)
			(layer "F.Fab")
		)
		(fp_line
			(start 0.875 -0.475)
			(end -0.875 -0.475)
			(stroke
				(width 0.2)
				(type solid)
			)
			(layer "F.Fab")
		)
		(fp_line
			(start 0.5 0)
			(end -0.5 0)
			(stroke
				(width 0.1)
				(type solid)
			)
			(layer "F.Fab")
		)
		(fp_line
			(start 0 -0.5)
			(end 0 0.5)
			(stroke
				(width 0.1)
				(type solid)
			)
			(layer "F.Fab")
		)
		(fp_line
			(start -0.875 -0.475)
			(end -0.875 0.475)
			(stroke
				(width 0.2)
				(type solid)
			)
			(layer "F.Fab")
		)
		(fp_text user "${REFERENCE}"
			(at -0.00001 0.09601 180)
			(unlocked yes)
			(layer "F.Fab")
			(effects
				(font
					(face "Arial")
					(size 0.63 0.63)
					(thickness 0.1)
				)
				(justify left bottom)
			)
		)
		(pad "1" smd rect
			(at -0.5 0 180)
			(size 0.5 0.5)
			(layers "F.Cu" "F.Mask" "F.Paste")
			(net "NetC91_1")
			(solder_mask_margin 0)
			(solder_paste_margin 0)
		)
		(pad "2" smd rect
			(at 0.5 0 180)
			(size 0.5 0.5)
			(layers "F.Cu" "F.Mask" "F.Paste")
			(net "GND")
			(solder_mask_margin 0)
			(solder_paste_margin 0)
		)
	)
	(footprint "Vault:CAPC1005X55X25ML05T05"
		(layer "F.Cu")
		(at 120.18072 87.9662 90)
		(property "Reference" "C68"
			(at -2.0214 0.067811 90)
			(unlocked yes)
			(layer "F.SilkS")
			(effects
				(font
					(size 0.762 0.762)
					(thickness 0.2286)
				)
			)
		)
		(property "Value" "22pF_50V_0402"
			(at -3.011671 9.68682 0)
			(unlocked yes)
			(layer "F.SilkS")
			(hide yes)
			(effects
				(font
					(size 0.762 0.762)
					(thickness 0.2286)
				)
			)
		)
		(sheetname "05-GPS_IMU_SENSORS")
		(sheetfile "05-GPS_IMU_SENSORS.kicad_sch")
		(duplicate_pad_numbers_are_jumpers no)
		(pad "1" smd rect
			(at -0.51 0 180)
			(size 0.72 0.72)
			(layers "F.Cu" "F.Mask" "F.Paste")
			(net "GND")
		)
		(pad "2" smd rect
			(at 0.51 0 180)
			(size 0.72 0.72)
			(layers "F.Cu" "F.Mask" "F.Paste")
			(net "BNO_XOUT32")
		)
	)
	(footprint "Vault:RESC1005X40X25LL05T10"
		(layer "F.Cu")
		(at 146.6216 104.4162)
		(property "Reference" "R106"
			(at 2.5286 0.226931 0)
			(unlocked yes)
			(layer "F.SilkS")
			(effects
				(font
					(size 0.762 0.762)
					(thickness 0.2286)
				)
			)
		)
		(property "Value" "DNI_49.9_1%_0402"
			(at -2.579871 11.74372 270)
			(unlocked yes)
			(layer "F.SilkS")
			(hide yes)
			(effects
				(font
					(size 0.762 0.762)
					(thickness 0.2286)
				)
			)
		)
		(sheetname "09-USBUart_PPSMUX_UARTMUX")
		(sheetfile "09-USBUart_PPSMUX_UARTMUX.kicad_sch")
		(duplicate_pad_numbers_are_jumpers no)
		(pad "1" smd rect
			(at -0.375 0 90)
			(size 0.45 0.5)
			(layers "F.Cu" "F.Mask" "F.Paste")
			(net "FPGA_MAC_PPS_IN0-")
		)
		(pad "2" smd rect
			(at 0.375 0 90)
			(size 0.45 0.5)
			(layers "F.Cu" "F.Mask" "F.Paste")
			(net "MAC_PPS_IN")
		)
	)
)
